# BASEBOARD_FAB2 (Tioga Pass) — schematic netlist excerpt (pin names and nets, part order shuffled) for the footprints in the layout excerpt that follows; sources: Cadence DE-HDL packaged netlist, KiCad conversion of Wiwynn_Tioga_Pass_MB.brd

RT6  1R3F-GP  1%  pkg RCL_GP  page 227 : \1\ = VR_PVDDQ_KLM_PH1_RC ; \2\ = GND
C4A6  CAP  1000PF 50V 10% EMPTY  pkg 0402LF  page 230 : A = FM_PVTT_KLM_EN_R ; B = GND
RT3  RES  0 5.0% CHIP  pkg 0603  page 202 : A = VR_PVCCIN_CPU0_PH2_BOOT ; B = VR_PVCCIN_CPU0_PH2_BOOT_R

(kicad_pcb
	(version 20260206)
	(generator "pcbnew")
	(generator_version "10.0")
	(general
		(thickness 1.6)
		(legacy_teardrops no)
	)
	(paper "A4")
	(title_block
		(title "Wiwynn_Tioga_Pass_MB.brd")
		(comment 1 "Tioga Pass / footprints 848-850 of 4770")
	)
	(layers
		(0 "F.Cu" signal "TOP")
		(4 "In1.Cu" signal "L2GND")
		(6 "In2.Cu" signal "L3")
		(8 "In3.Cu" signal "L4GND")
		(10 "In4.Cu" signal "L5")
		(12 "In5.Cu" signal "L6GND")
		(14 "In6.Cu" signal "L7VCC")
		(16 "In7.Cu" signal "L8VCC")
		(18 "In8.Cu" signal "L9GND")
		(20 "In9.Cu" signal "L10")
		(22 "In10.Cu" signal "L11GND")
		(24 "In11.Cu" signal "L12")
		(26 "In12.Cu" signal "L13GND")
		(2 "B.Cu" signal "BOTTOM")
		(9 "F.Adhes" user "F.Adhesive")
		(11 "B.Adhes" user "B.Adhesive")
		(13 "F.Paste" user "Package Geometry/Pastemask Top")
		(15 "B.Paste" user "Package Geometry/Pastemask Bottom")
		(5 "F.SilkS" user "Ref Des/Silkscreen Top")
		(7 "B.SilkS" user "Ref Des/Silkscreen Bottom")
		(1 "F.Mask" user "Board Geometry/Soldermask Top")
		(3 "B.Mask" user "Board Geometry/Soldermask Bottom")
		(17 "Dwgs.User" user "User.Drawings")
		(19 "Cmts.User" user "User.Comments")
		(21 "Eco1.User" user "User.Eco1")
		(23 "Eco2.User" user "User.Eco2")
		(25 "Edge.Cuts" user "Board Geometry/Outline")
		(27 "Margin" user)
		(31 "F.CrtYd" user "Package Geometry/Place Bound Top")
		(29 "B.CrtYd" user "Package Geometry/Place Bound Bottom")
		(35 "F.Fab" user "Ref Des/Assembly Top")
		(33 "B.Fab" user "Ref Des/Assembly Bottom")
	)
	(footprint ""
		(layer "F.Cu")
		(at 4.445 -134.3914 -90)
		(property "Reference" "RT6"
			(at 0 0 270)
			(layer "F.SilkS")
			(hide yes)
			(effects
				(font
					(size 1.27 1.27)
				)
			)
		)
		(property "Value" "*"
			(at -0.0254 -2.6289 270)
			(unlocked yes)
			(layer "F.Fab")
			(hide yes)
			(effects
				(font
					(size 1.27 1.016)
					(thickness 0.1524)
				)
			)
		)
		(property "Device Type" "1R3F-GP_RCL_GP-1R3F-GP,64.1R00A"
			(at -0.0254 -4.1529 270)
			(unlocked yes)
			(layer "F.Fab")
			(hide yes)
			(effects
				(font
					(size 1.27 1.016)
					(thickness 0.1524)
				)
			)
		)
		(duplicate_pad_numbers_are_jumpers no)
		(fp_line
			(start -0.4826 0)
			(end -0.2032 0)
			(stroke
				(width 0.2032)
				(type default)
			)
			(layer "F.SilkS")
		)
		(fp_line
			(start 0.2032 0)
			(end 0.4826 0)
			(stroke
				(width 0.2032)
				(type default)
			)
			(layer "F.SilkS")
		)
		(fp_rect
			(start -0.5842 1.3335)
			(end 0.5842 -1.3335)
			(stroke
				(width 0)
				(type default)
			)
			(fill no)
			(layer "F.CrtYd")
		)
		(fp_rect
			(start -0.5842 1.3335)
			(end 0.5842 -1.3335)
			(stroke
				(width 0)
				(type default)
			)
			(fill no)
			(layer "F.Fab")
		)
		(pad "1" smd custom
			(at 0 -0.762 270)
			(size 0.2159 0.2159)
			(layers "F.Cu" "F.Mask" "F.Paste")
			(net "VR_PVDDQ_KLM_PH1_RC")
			(options
				(clearance outline)
				(anchor circle)
			)
			(primitives
				(gr_poly
					(pts
						(arc
							(start -0.3302 -0.4318)
							(mid -0.402042 -0.402042)
							(end -0.4318 -0.3302)
						)
						(arc
							(start -0.4318 0.3302)
							(mid -0.402042 0.402042)
							(end -0.3302 0.4318)
						)
						(arc
							(start 0.3302 0.4318)
							(mid 0.402042 0.402042)
							(end 0.4318 0.3302)
						)
						(arc
							(start 0.4318 -0.3302)
							(mid 0.402042 -0.402042)
							(end 0.3302 -0.4318)
						)
					)
					(width 0)
					(fill yes)
				)
			)
		)
		(pad "2" smd custom
			(at 0 0.762 270)
			(size 0.2159 0.2159)
			(layers "F.Cu" "F.Mask" "F.Paste")
			(net "GND")
			(options
				(clearance outline)
				(anchor circle)
			)
			(primitives
				(gr_poly
					(pts
						(arc
							(start -0.3302 -0.4318)
							(mid -0.402042 -0.402042)
							(end -0.4318 -0.3302)
						)
						(arc
							(start -0.4318 0.3302)
							(mid -0.402042 0.402042)
							(end -0.3302 0.4318)
						)
						(arc
							(start 0.3302 0.4318)
							(mid 0.402042 0.402042)
							(end 0.4318 0.3302)
						)
						(arc
							(start 0.4318 -0.3302)
							(mid 0.402042 -0.402042)
							(end 0.3302 -0.4318)
						)
					)
					(width 0)
					(fill yes)
				)
			)
		)
	)
	(footprint ""
		(layer "F.Cu")
		(at 167.4876 -149.225 -90)
		(property "Reference" "C4A6"
			(at 0 0 270)
			(layer "F.SilkS")
			(hide yes)
			(effects
				(font
					(size 1.27 1.27)
				)
			)
		)
		(property "Value" ""
			(at 0 0 270)
			(layer "F.Fab")
			(effects
				(font
					(size 1.27 1.27)
				)
			)
		)
		(duplicate_pad_numbers_are_jumpers no)
		(fp_rect
			(start -0.3048 -0.1016)
			(end 0.3048 0.9906)
			(stroke
				(width 0)
				(type default)
			)
			(fill no)
			(layer "F.CrtYd")
		)
		(fp_line
			(start -0.3048 0.9906)
			(end 0.3048 0.9906)
			(stroke
				(width 0.1)
				(type default)
			)
			(layer "F.Fab")
		)
		(fp_line
			(start 0.3048 0.9906)
			(end 0.3048 -0.1016)
			(stroke
				(width 0.1)
				(type default)
			)
			(layer "F.Fab")
		)
		(fp_line
			(start -0.3048 -0.1016)
			(end -0.3048 0.9906)
			(stroke
				(width 0.1)
				(type default)
			)
			(layer "F.Fab")
		)
		(fp_line
			(start 0.3048 -0.1016)
			(end -0.3048 -0.1016)
			(stroke
				(width 0.1)
				(type default)
			)
			(layer "F.Fab")
		)
		(pad "1" smd rect
			(at 0 0 270)
			(size 0.508 0.508)
			(layers "F.Cu" "F.Mask" "F.Paste")
			(net "FM_PVTT_KLM_EN_R")
		)
		(pad "2" smd rect
			(at 0 0.889 270)
			(size 0.508 0.508)
			(layers "F.Cu" "F.Mask" "F.Paste")
			(net "GND")
		)
		(zone
			(layer "F.Cu")
			(hatch none 0.5)
			(connect_pads
				(clearance 0)
			)
			(min_thickness 0.25)
			(keepout
				(tracks allowed)
				(vias not_allowed)
				(pads allowed)
				(copperpour not_allowed)
				(footprints allowed)
			)
			(placement
				(enabled no)
				(sheetname "")
			)
			(fill
				(thermal_gap 0.5)
				(thermal_bridge_width 0.5)
				(island_removal_mode 0)
			)
			(polygon
				(pts
					(xy 167.2336 -149.479) (xy 166.8526 -149.479) (xy 166.8526 -148.971) (xy 167.2336 -148.971)
				)
			)
		)
		(zone
			(layer "F.Cu")
			(hatch none 0.5)
			(connect_pads
				(clearance 0)
			)
			(min_thickness 0.25)
			(keepout
				(tracks not_allowed)
				(vias allowed)
				(pads allowed)
				(copperpour not_allowed)
				(footprints allowed)
			)
			(placement
				(enabled no)
				(sheetname "")
			)
			(fill
				(thermal_gap 0.5)
				(thermal_bridge_width 0.5)
				(island_removal_mode 0)
			)
			(polygon
				(pts
					(xy 167.2336 -149.479) (xy 166.8526 -149.479) (xy 166.8526 -148.971) (xy 167.2336 -148.971)
				)
			)
		)
	)
	(footprint ""
		(layer "F.Cu")
		(at 192.786 -66.06667 90)
		(property "Reference" "RT3"
			(at 1.01473 0.656336 0)
			(unlocked yes)
			(layer "F.SilkS")
			(effects
				(font
					(size 0.4064 0.254)
					(thickness 0.1524)
				)
			)
		)
		(property "Value" ""
			(at 0 0 90)
			(layer "F.Fab")
			(effects
				(font
					(size 1.27 1.27)
				)
			)
		)
		(duplicate_pad_numbers_are_jumpers no)
		(fp_poly
			(pts
				(xy -0.4953 -0.2032) (xy 0.4953 -0.2032) (xy 0.4953 1.6002) (xy -0.4953 1.6002)
			)
			(stroke
				(width 0)
				(type default)
			)
			(fill no)
			(layer "F.CrtYd")
		)
		(fp_line
			(start 0.4953 -0.2032)
			(end 0.4953 1.6002)
			(stroke
				(width 0.1)
				(type default)
			)
			(layer "F.Fab")
		)
		(fp_line
			(start -0.4953 -0.2032)
			(end 0.4953 -0.2032)
			(stroke
				(width 0.1)
				(type default)
			)
			(layer "F.Fab")
		)
		(fp_line
			(start 0.4953 1.6002)
			(end -0.4953 1.6002)
			(stroke
				(width 0.1)
				(type default)
			)
			(layer "F.Fab")
		)
		(fp_line
			(start -0.4953 1.6002)
			(end -0.4953 -0.2032)
			(stroke
				(width 0.1)
				(type default)
			)
			(layer "F.Fab")
		)
		(pad "1" smd rect
			(at 0 0 90)
			(size 0.762 0.889)
			(layers "F.Cu" "F.Mask" "F.Paste")
			(net "VR_PVCCIN_CPU0_PH2_BOOT")
		)
		(pad "2" smd rect
			(at 0 1.397 90)
			(size 0.762 0.889)
			(layers "F.Cu" "F.Mask" "F.Paste")
			(net "VR_PVCCIN_CPU0_PH2_BOOT_R")
		)
		(zone
			(layer "F.Cu")
			(hatch none 0.5)
			(connect_pads
				(clearance 0)
			)
			(min_thickness 0.25)
			(keepout
				(tracks allowed)
				(vias not_allowed)
				(pads allowed)
				(copperpour not_allowed)
				(footprints allowed)
			)
			(placement
				(enabled no)
				(sheetname "")
			)
			(fill
				(thermal_gap 0.5)
				(thermal_bridge_width 0.5)
				(island_removal_mode 0)
			)
			(polygon
				(pts
					(xy 193.7385 -66.44767) (xy 193.2305 -66.44767) (xy 193.2305 -65.68567) (xy 193.7385 -65.68567)
				)
			)
		)
		(zone
			(layer "F.Cu")
			(hatch none 0.5)
			(connect_pads
				(clearance 0)
			)
			(min_thickness 0.25)
			(keepout
				(tracks not_allowed)
				(vias allowed)
				(pads allowed)
				(copperpour not_allowed)
				(footprints allowed)
			)
			(placement
				(enabled no)
				(sheetname "")
			)
			(fill
				(thermal_gap 0.5)
				(thermal_bridge_width 0.5)
				(island_removal_mode 0)
			)
			(polygon
				(pts
					(xy 193.7385 -65.68567) (xy 193.7385 -66.44767) (xy 193.2305 -66.44767) (xy 193.2305 -65.68567)
				)
			)
		)
	)
)
